# S9S_MB_2U (Grand Teton) — schematic netlist excerpt (pin names and nets, part order shuffled) for the footprints in the layout excerpt that follows; sources: Cadence DE-HDL packaged netlist, KiCad conversion of 03242023_DA0F0TMBIJ0_F0T_Motherboard_J_brd_V01_OCP.brd

D49  SCHOTTKY_12  B0530WS7F IC  pkg SOD323XB  page 115 : A = PWRGD_FAIL_CPU1_GH_R1 ; C = P3V3_AUX
R594  Q_RES  0 5% CHIP  pkg 0402LF  page 241 : A = I3C_SPD_DDRABCD_CPU0_BMC_R_SDA ; B = I3C_SPD_DDRABCD_CPU0_BMC_SDA

(kicad_pcb
	(version 20260206)
	(generator "pcbnew")
	(generator_version "10.0")
	(general
		(thickness 1.6)
		(legacy_teardrops no)
	)
	(paper "A4")
	(title_block
		(title "03242023_DA0F0TMBIJ0_F0T_Motherboard_J_brd_V01_OCP.brd")
		(comment 1 "Grand Teton / footprints 5819-5820 of 6105")
	)
	(layers
		(0 "F.Cu" signal "TOP")
		(4 "In1.Cu" signal "GND")
		(6 "In2.Cu" signal "IN1")
		(8 "In3.Cu" signal "GND1")
		(10 "In4.Cu" signal "IN2")
		(12 "In5.Cu" signal "GND2")
		(14 "In6.Cu" signal "IN3")
		(16 "In7.Cu" signal "GND3")
		(18 "In8.Cu" signal "VCC")
		(20 "In9.Cu" signal "VCC1")
		(22 "In10.Cu" signal "GND4")
		(24 "In11.Cu" signal "IN4")
		(26 "In12.Cu" signal "GND5")
		(28 "In13.Cu" signal "IN5")
		(30 "In14.Cu" signal "GND6")
		(32 "In15.Cu" signal "IN6")
		(34 "In16.Cu" signal "GND7")
		(2 "B.Cu" signal "BOTTOM")
		(9 "F.Adhes" user "F.Adhesive")
		(11 "B.Adhes" user "B.Adhesive")
		(13 "F.Paste" user "Package Geometry/Pastemask Top")
		(15 "B.Paste" user "Package Geometry/Pastemask Bottom")
		(5 "F.SilkS" user "Ref Des/Silkscreen Top")
		(7 "B.SilkS" user "Ref Des/Silkscreen Bottom")
		(1 "F.Mask" user "Board Geometry/Soldermask Top")
		(3 "B.Mask" user "Board Geometry/Soldermask Bottom")
		(17 "Dwgs.User" user "User.Drawings")
		(19 "Cmts.User" user "User.Comments")
		(21 "Eco1.User" user "User.Eco1")
		(23 "Eco2.User" user "User.Eco2")
		(25 "Edge.Cuts" user "Board Geometry/Outline")
		(27 "Margin" user)
		(31 "F.CrtYd" user "Package Geometry/Place Bound Top")
		(29 "B.CrtYd" user "Package Geometry/Place Bound Bottom")
		(35 "F.Fab" user "Ref Des/Assembly Top")
		(33 "B.Fab" user "Ref Des/Assembly Bottom")
	)
	(footprint ""
		(layer "B.Cu")
		(at 189.350396 -13.60043 -90)
		(property "Reference" "R594"
			(at 0 0 90)
			(layer "B.SilkS")
			(hide yes)
			(effects
				(font
					(size 1.27 1.27)
				)
				(justify mirror)
			)
		)
		(property "Value" ""
			(at 0 0 90)
			(layer "B.Fab")
			(effects
				(font
					(size 1.27 1.27)
				)
				(justify mirror)
			)
		)
		(duplicate_pad_numbers_are_jumpers no)
		(fp_line
			(start -0.7874 0.4064)
			(end 0.7874 0.4064)
			(stroke
				(width 0.1524)
				(type default)
			)
			(layer "B.SilkS")
		)
		(fp_line
			(start 0.7874 0.4064)
			(end 0.7874 -0.4064)
			(stroke
				(width 0.1524)
				(type default)
			)
			(layer "B.SilkS")
		)
		(fp_line
			(start -0.7874 -0.4064)
			(end -0.7874 0.4064)
			(stroke
				(width 0.1524)
				(type default)
			)
			(layer "B.SilkS")
		)
		(fp_line
			(start 0.7874 -0.4064)
			(end -0.7874 -0.4064)
			(stroke
				(width 0.1524)
				(type default)
			)
			(layer "B.SilkS")
		)
		(fp_line
			(start -0.67945 0.3048)
			(end -0.120396 0.3048)
			(stroke
				(width 0.1)
				(type default)
			)
			(layer "B.Fab")
		)
		(fp_line
			(start -0.120396 0.3048)
			(end -0.120396 0.2794)
			(stroke
				(width 0.1)
				(type default)
			)
			(layer "B.Fab")
		)
		(fp_line
			(start 0.12065 0.3048)
			(end 0.67945 0.3048)
			(stroke
				(width 0.1)
				(type default)
			)
			(layer "B.Fab")
		)
		(fp_line
			(start 0.67945 0.3048)
			(end 0.67945 -0.305054)
			(stroke
				(width 0.1)
				(type default)
			)
			(layer "B.Fab")
		)
		(fp_line
			(start -0.120396 0.2794)
			(end 0.12065 0.2794)
			(stroke
				(width 0.1)
				(type default)
			)
			(layer "B.Fab")
		)
		(fp_line
			(start 0.12065 0.2794)
			(end 0.12065 0.3048)
			(stroke
				(width 0.1)
				(type default)
			)
			(layer "B.Fab")
		)
		(fp_line
			(start -0.12065 -0.2794)
			(end -0.12065 -0.3048)
			(stroke
				(width 0.1)
				(type default)
			)
			(layer "B.Fab")
		)
		(fp_line
			(start 0.12065 -0.2794)
			(end -0.12065 -0.2794)
			(stroke
				(width 0.1)
				(type default)
			)
			(layer "B.Fab")
		)
		(fp_line
			(start -0.67945 -0.3048)
			(end -0.67945 0.3048)
			(stroke
				(width 0.1)
				(type default)
			)
			(layer "B.Fab")
		)
		(fp_line
			(start -0.12065 -0.3048)
			(end -0.67945 -0.3048)
			(stroke
				(width 0.1)
				(type default)
			)
			(layer "B.Fab")
		)
		(fp_line
			(start 0.12065 -0.305054)
			(end 0.12065 -0.2794)
			(stroke
				(width 0.1)
				(type default)
			)
			(layer "B.Fab")
		)
		(fp_line
			(start 0.67945 -0.305054)
			(end 0.12065 -0.305054)
			(stroke
				(width 0.1)
				(type default)
			)
			(layer "B.Fab")
		)
		(pad "1" smd circle
			(at 0.40005 0 90)
			(size 0 0)
			(layers "B.Cu" "B.Mask" "B.Paste")
			(net "I3C_SPD_DDRABCD_CPU0_BMC_R_SDA")
		)
		(pad "2" smd circle
			(at -0.40005 0 90)
			(size 0 0)
			(layers "B.Cu" "B.Mask" "B.Paste")
			(net "I3C_SPD_DDRABCD_CPU0_BMC_SDA")
		)
	)
	(footprint ""
		(layer "B.Cu")
		(at 211.634578 -316.14999 -90)
		(property "Reference" "D49"
			(at 4.116832 1.530858 0)
			(unlocked yes)
			(layer "B.SilkS")
			(effects
				(font
					(size 0.7874 0.5842)
					(thickness 0.1524)
				)
				(justify left mirror)
			)
		)
		(property "Value" ""
			(at 0 0 90)
			(layer "B.Fab")
			(effects
				(font
					(size 1.27 1.27)
				)
				(justify mirror)
			)
		)
		(duplicate_pad_numbers_are_jumpers no)
		(fp_line
			(start -2.050796 0.700024)
			(end 2.050796 0.700024)
			(stroke
				(width 0.1524)
				(type default)
			)
			(layer "B.SilkS")
		)
		(fp_line
			(start 2.050796 0.700024)
			(end 2.050796 -0.700024)
			(stroke
				(width 0.1524)
				(type default)
			)
			(layer "B.SilkS")
		)
		(fp_line
			(start -2.343404 0.6985)
			(end -2.216404 0.6985)
			(stroke
				(width 0.1524)
				(type default)
			)
			(layer "B.SilkS")
		)
		(fp_line
			(start -2.229104 0.6985)
			(end -2.051304 0.6985)
			(stroke
				(width 0.1524)
				(type default)
			)
			(layer "B.SilkS")
		)
		(fp_line
			(start -2.051304 0.6985)
			(end -2.051304 0.635)
			(stroke
				(width 0.1524)
				(type default)
			)
			(layer "B.SilkS")
		)
		(fp_line
			(start -2.152904 0.635)
			(end -2.152904 -0.6985)
			(stroke
				(width 0.1524)
				(type default)
			)
			(layer "B.SilkS")
		)
		(fp_line
			(start -2.051304 0.635)
			(end -2.152904 0.635)
			(stroke
				(width 0.1524)
				(type default)
			)
			(layer "B.SilkS")
		)
		(fp_line
			(start 0.30607 0.500126)
			(end -0.193802 0)
			(stroke
				(width 0.1524)
				(type default)
			)
			(layer "B.SilkS")
		)
		(fp_line
			(start -0.193802 0)
			(end 0.30607 -0.500126)
			(stroke
				(width 0.1524)
				(type default)
			)
			(layer "B.SilkS")
		)
		(fp_line
			(start -0.293878 -0.500126)
			(end -0.293878 0.500126)
			(stroke
				(width 0.1524)
				(type default)
			)
			(layer "B.SilkS")
		)
		(fp_line
			(start 0.30607 -0.500126)
			(end 0.30607 0.500126)
			(stroke
				(width 0.1524)
				(type default)
			)
			(layer "B.SilkS")
		)
		(fp_line
			(start -2.064004 -0.6731)
			(end -2.064004 -0.6985)
			(stroke
				(width 0.1524)
				(type default)
			)
			(layer "B.SilkS")
		)
		(fp_line
			(start -2.343404 -0.6985)
			(end -2.343404 0.6985)
			(stroke
				(width 0.1524)
				(type default)
			)
			(layer "B.SilkS")
		)
		(fp_line
			(start -2.229104 -0.6985)
			(end -2.229104 0.6985)
			(stroke
				(width 0.1524)
				(type default)
			)
			(layer "B.SilkS")
		)
		(fp_line
			(start -2.152904 -0.6985)
			(end -2.343404 -0.6985)
			(stroke
				(width 0.1524)
				(type default)
			)
			(layer "B.SilkS")
		)
		(fp_line
			(start -2.064004 -0.6985)
			(end -2.229104 -0.6985)
			(stroke
				(width 0.1524)
				(type default)
			)
			(layer "B.SilkS")
		)
		(fp_line
			(start -2.050796 -0.700024)
			(end -2.050796 0.700024)
			(stroke
				(width 0.1524)
				(type default)
			)
			(layer "B.SilkS")
		)
		(fp_line
			(start 2.050796 -0.700024)
			(end -2.050796 -0.700024)
			(stroke
				(width 0.1524)
				(type default)
			)
			(layer "B.SilkS")
		)
		(fp_line
			(start -0.899922 0.700024)
			(end 0.899922 0.700024)
			(stroke
				(width 0.1)
				(type default)
			)
			(layer "B.Fab")
		)
		(fp_line
			(start 0.899922 0.700024)
			(end 0.899922 -0.700024)
			(stroke
				(width 0.1)
				(type default)
			)
			(layer "B.Fab")
		)
		(fp_line
			(start -0.899922 -0.700024)
			(end -0.899922 0.700024)
			(stroke
				(width 0.1)
				(type default)
			)
			(layer "B.Fab")
		)
		(fp_line
			(start 0.899922 -0.700024)
			(end -0.899922 -0.700024)
			(stroke
				(width 0.1)
				(type default)
			)
			(layer "B.Fab")
		)
		(fp_text user "-"
			(at -0.268478 1.839468 90)
			(unlocked yes)
			(layer "B.SilkS")
			(effects
				(font
					(size 1.905 1.4224)
					(thickness 0.1524)
				)
				(justify left mirror)
			)
		)
		(fp_text user "+"
			(at 3.123946 0.762 180)
			(unlocked yes)
			(layer "B.SilkS")
			(effects
				(font
					(size 1.905 1.4224)
					(thickness 0.1524)
				)
				(justify left mirror)
			)
		)
		(fp_text user "+"
			(at 3.123946 0.762 180)
			(unlocked yes)
			(layer "B.Fab")
			(effects
				(font
					(size 1.905 1.4224)
					(thickness 0.1524)
				)
				(justify left mirror)
			)
		)
		(fp_text user "-"
			(at -3.880104 0.23495 90)
			(unlocked yes)
			(layer "B.Fab")
			(effects
				(font
					(size 1.905 1.4224)
					(thickness 0.1524)
				)
				(justify left mirror)
			)
		)
		(pad "1" smd rect
			(at 1.199896 0 180)
			(size 0.6604 1.3716)
			(layers "B.Cu" "B.Mask" "B.Paste")
			(net "PWRGD_FAIL_CPU1_GH_R1")
		)
		(pad "2" smd rect
			(at -1.199896 0)
			(size 0.6604 1.3716)
			(layers "B.Cu" "B.Mask" "B.Paste")
			(net "P3V3_AUX")
		)
	)
)
